M48
INCH,TZ
T01C.012
T02C.101
T03C.086
T04C.115
;LEADER: 12 
;HEADER: 
;CODE  : ASCII 
;FILE  : 16347-sc-1-2.drl for board 16347-sc.brd ... layers TOP and BOTTOM
;T01 Holesize 1. = 12.000000 Tolerance = +0.000000/-0.000000 PLATED MILS Quantity = 156
;T02 Holesize 2. = 101.000000 Tolerance = +0.000000/-0.000000 PLATED MILS Quantity = 4
;T03 Holesize 3. = 86.000000 Tolerance = +0.000000/-0.000000 NON_PLATED MILS Quantity = 16
;T04 Holesize 4. = 115.000000 Tolerance = +0.000000/-0.000000 NON_PLATED MILS Quantity = 2
%
G90
T01
X4758Y4649
X5223Y34706
X30374Y34551
X38675Y22425
X20459Y5682
X35539Y4546
X59871Y19900
X54026Y28870
X46376Y36160
X41942Y46869
X55513Y51513
X51573Y51573
X59100Y56200
X47800Y56500
X42071Y58644
X65100Y59000
X65000Y45100
X76200Y35200
X71000Y11600
X63477Y4598
X90368Y245
X84600Y12000
X99000Y35000
X102586Y30227
X112024Y30080
X100000Y16500
X111100Y10400
X113912Y245
X124500Y12100
X139300Y19000
X126106Y29996
X135500Y29976
X145200Y26300
X140900Y23800
X145601Y245
X174542Y4205
X179537Y9829
X165593Y21701
X162191Y24351
X164378Y52020
X164200Y62000
X175800Y67500
X197800
X191500Y63910
X195500
X199700
X189652Y8444
X202034Y4247
X219878Y32075
X217446Y46840
Y51035
X216500Y67500
X222700Y60100
X233765Y34883
X238755Y26619
X225477Y20626
X238391Y14434
X249762Y12946
X241359Y21413
X245853Y31620
X256656Y35189
X265042Y13093
X279170Y35245
X283197Y20870
X290350Y46275
X296005Y55029
X290660Y58851
X313500Y58100
X307599Y54564
X302200Y51718
X304088Y48291
X313200Y45500
X316800Y35900
X323200Y13800
X330300Y26000
X339400Y34800
X348900Y13700
X365800Y26400
X384600Y34800
X394400Y26300
X383600Y14000
X414700Y13800
X404600Y14400
X405000Y20700
X402400Y34800
X414600Y44600
X414700Y58000
X436012Y59651
X431894Y54627
X420635Y54538
X428151Y52151
X424211Y52000
X437768Y51052
X438311Y39148
X428600Y13800
X446135Y10537
X455689Y15598
X447000Y20700
X455817Y26237
X448019Y35172
X462893
X473300Y25875
X473919Y10744
X501900Y10348
X516716Y15930
X518856Y25583
X503159Y35111
X532070Y10129
X531500Y20300
X529979Y35111
X538911Y42406
X538954Y59320
X544789Y54552
X555996Y54409
X552364Y52136
X548424Y52000
X541225Y13900
X554500Y13000
X563034Y312
X574168Y7737
X573300Y20500
X565606Y36026
X561619Y47946
X561954Y58858
X581051Y35186
X580014Y25376
X580128Y14830
X601510Y277
X617398Y7695
X614586Y25544
X615510Y35060
X623300Y19600
X625457Y14410
X632900Y13300
X628333Y278
X646777Y311
X647600Y12500
X644052Y35251
X662275Y4597
X671342Y13872
X665500Y19700
X670753Y27514
X663106Y43749
X672636Y52380
X676576
X668373Y54326
X663022Y59320
X685686Y59530
X680189Y54619
X686484Y39279
X695912Y18399
X684016Y4178
X704646Y4135
X701971Y35249
X723902Y35018
X724174Y4463
T02
X16240Y19684
X301968Y19685
X488681Y19684
X712106
T03
X35185Y15572
X16240Y99213
Y233859
Y368505
Y503151
Y637797
Y772443
Y907089
X693024Y26550
X784745Y19685
Y154331
Y288977
Y423623
Y558269
Y692915
Y827561
T04
X47737Y19685
X680610
M30
